(kicad_pcb
	(version 20260206)
	(generator "pcbnew")
	(generator_version "10.0")
	(general
		(thickness 1.6)
		(legacy_teardrops no)
	)
	(paper "A4")
	(title_block
		(title "v1-tray-backplane — T6M_tray_BP_c_1023_1120.brd")
		(comment 1 "Open CloudServer (Microsoft) / footprint 101 of 170 (U10), pads 1-12 of 12")
	)
	(layers
		(0 "F.Cu" signal "TOP")
		(4 "In1.Cu" signal "GND")
		(6 "In2.Cu" signal "IN1")
		(8 "In3.Cu" signal "VCC")
		(10 "In4.Cu" signal "VCC1")
		(12 "In5.Cu" signal "IN2")
		(14 "In6.Cu" signal "GND1")
		(2 "B.Cu" signal "BOTTOM")
		(9 "F.Adhes" user "F.Adhesive")
		(11 "B.Adhes" user "B.Adhesive")
		(13 "F.Paste" user "Package Geometry/Pastemask Top")
		(15 "B.Paste" user "Package Geometry/Pastemask Bottom")
		(5 "F.SilkS" user "Ref Des/Silkscreen Top")
		(7 "B.SilkS" user "Ref Des/Silkscreen Bottom")
		(1 "F.Mask" user "Board Geometry/Soldermask Top")
		(3 "B.Mask" user "Board Geometry/Soldermask Bottom")
		(17 "Dwgs.User" user "User.Drawings")
		(19 "Cmts.User" user "User.Comments")
		(21 "Eco1.User" user "User.Eco1")
		(23 "Eco2.User" user "User.Eco2")
		(25 "Edge.Cuts" user "Board Geometry/Outline")
		(27 "Margin" user)
		(31 "F.CrtYd" user "Package Geometry/Place Bound Top")
		(29 "B.CrtYd" user "Package Geometry/Place Bound Bottom")
		(35 "F.Fab" user "Ref Des/Assembly Top")
		(33 "B.Fab" user "Ref Des/Assembly Bottom")
	)
	(footprint ""
		(layer "F.Cu")
		(at 181.987952 -33.589976)
		(property "Reference" "U10"
			(at -21.817076 -12.088876 90)
			(unlocked yes)
			(layer "F.SilkS")
			(effects
				(font
					(size 0.7874 0.5842)
					(thickness 0.1524)
				)
				(justify left)
			)
		)
		(property "Value" ""
			(at 0 0 0)
			(layer "F.Fab")
			(effects
				(font
					(size 1.27 1.27)
				)
			)
		)
		(duplicate_pad_numbers_are_jumpers no)
		(pad "A1" smd rect
			(at 12.109958 12.62507)
			(size 0.9144 2.1336)
			(layers "F.Cu" "F.Mask" "F.Paste")
			(net "GND")
		)
		(pad "A2" smd rect
			(at 9.709912 12.62507)
			(size 0.9144 2.1336)
			(layers "F.Cu" "F.Mask" "F.Paste")
			(net "GND")
		)
		(pad "A3" smd rect
			(at 7.31012 12.62507)
			(size 0.9144 2.1336)
			(layers "F.Cu" "F.Mask" "F.Paste")
			(net "GND")
		)
		(pad "B1" smd rect
			(at -6.89991 12.62507)
			(size 0.9144 2.1336)
			(layers "F.Cu" "F.Mask" "F.Paste")
			(net "GND")
		)
		(pad "B2" smd rect
			(at -9.299956 12.62507)
			(size 0.9144 2.1336)
			(layers "F.Cu" "F.Mask" "F.Paste")
			(net "GND")
		)
		(pad "B3" smd rect
			(at -11.700002 12.62507)
			(size 0.9144 2.1336)
			(layers "F.Cu" "F.Mask" "F.Paste")
			(net "GND")
		)
		(pad "G1" thru_hole circle
			(at -19.61007 -8.999982)
			(size 3.5306 3.5306)
			(drill 2.5146)
			(layers "*.Cu" "*.Mask")
			(remove_unused_layers no)
			(net "GND")
			(clearance -0.254)
		)
		(pad "G2" thru_hole circle
			(at -19.120104 0)
			(size 2.3368 2.3368)
			(drill 1.5748)
			(layers "*.Cu" "*.Mask")
			(remove_unused_layers no)
			(net "GND")
			(clearance -0.127)
		)
		(pad "G3" thru_hole circle
			(at -19.61007 5.999988)
			(size 3.5306 3.5306)
			(drill 2.5146)
			(layers "*.Cu" "*.Mask")
			(remove_unused_layers no)
			(net "GND")
			(clearance -0.254)
		)
		(pad "G4" thru_hole circle
			(at 19.61007 -8.999982)
			(size 3.5306 3.5306)
			(drill 2.5146)
			(layers "*.Cu" "*.Mask")
			(remove_unused_layers no)
			(net "GND")
			(clearance -0.254)
		)
		(pad "G5" thru_hole circle
			(at 19.120104 0)
			(size 2.3368 2.3368)
			(drill 1.5748)
			(layers "*.Cu" "*.Mask")
			(remove_unused_layers no)
			(net "GND")
			(clearance -0.127)
		)
		(pad "G6" thru_hole circle
			(at 19.61007 5.999988)
			(size 3.5306 3.5306)
			(drill 2.5146)
			(layers "*.Cu" "*.Mask")
			(remove_unused_layers no)
			(net "GND")
			(clearance -0.254)
		)
	)
)
